# BARRELEYE_G2-FPDB_POST-EVT-HW-EBOM-X00_20161123-add_2nd_source_X08-20161215-Final-b.xls — TLA (bom)
| FOXCONN TECHNOLOGY GROUP |  |  |  |  |  |  |  |  |  |
| BILL OF MATERIAL |  |  |  |  |  |  |  |  |  |
| AA P/N | 1A42G4V00-600-G | CUSTOMER | <name> | Customer P/N |  | Product Code |  |  |  |
| PWA P/N |  | PWA DESCRIPTION | 風扇及電源分配板,ASSY,FPDB BOARD,G,BARRELEYE G2,RACKSPACE |  |  | PWA REV |  | Prepared By SE |  |
| Item | FOXCONN P/N | Customer P/N | Part Description | Manufacturer  Full Name | Manufacturer  Part Number | Qty | RoHS Status | Location | Remark |
| 1 | 7J-004-938 |  | L6 LABEL ( 12.7*11.1mm) | FOXCONN / EPD1 | 7J-004-938 | 2 | G |  | ID label for two boards. FPDB AA P/N: 1A42G4V00-600-G Post card AA P/N: 1A42GQG00-600-G |
